(kicad_pcb
	(version 20241229)
	(generator "pcbnew")
	(generator_version "9.0")
	(general
		(thickness 1.61)
		(legacy_teardrops no)
	)
	(paper "A3")
	(title_block
		(title "SO-DIMM DDR5 Tester")
		(date "2025-11-26")
		(rev "1.3.0")
		(comment 9 "footprints 257-261 of 627")
	)
	(layers
		(0 "F.Cu" signal)
		(4 "In1.Cu" power)
		(6 "In2.Cu" mixed)
		(8 "In3.Cu" power)
		(10 "In4.Cu" mixed)
		(12 "In5.Cu" power)
		(14 "In6.Cu" mixed)
		(16 "In7.Cu" power)
		(18 "In8.Cu" power)
		(20 "In9.Cu" mixed)
		(22 "In10.Cu" power)
		(2 "B.Cu" signal)
		(9 "F.Adhes" user "F.Adhesive")
		(11 "B.Adhes" user "B.Adhesive")
		(13 "F.Paste" user)
		(15 "B.Paste" user)
		(5 "F.SilkS" user "F.Silkscreen")
		(7 "B.SilkS" user "B.Silkscreen")
		(1 "F.Mask" user)
		(3 "B.Mask" user)
		(17 "Dwgs.User" user "User.Drawings")
		(19 "Cmts.User" user "User.Comments")
		(21 "Eco1.User" user "User.Eco1")
		(23 "Eco2.User" user "User.Eco2")
		(25 "Edge.Cuts" user)
		(27 "Margin" user)
		(31 "F.CrtYd" user "F.Courtyard")
		(29 "B.CrtYd" user "B.Courtyard")
		(35 "F.Fab" user)
		(33 "B.Fab" user)
	)
	(footprint "antmicro-footprints:R_0402_1005Metric"
		(layer "F.Cu")
		(at 99.850501 120.291 -90)
		(descr "Resistor SMD 0402")
		(tags "resistor SMD 0402")
		(property "Reference" "R62"
			(at -1.122484 -0.772697 270)
			(layer "F.SilkS")
			(hide yes)
			(effects
				(font
					(size 0.7 0.7)
					(thickness 0.15)
				)
				(justify left bottom)
			)
		)
		(property "Value" "R_330R_0402"
			(at -1.011843 1.772047 270)
			(layer "F.Fab")
			(effects
				(font
					(size 0.7 0.7)
					(thickness 0.15)
				)
				(justify left bottom)
			)
		)
		(property "Datasheet" "https://www.bourns.com/docs/product-datasheets/cr.pdf"
			(at 0 0 270)
			(layer "F.Fab")
			(hide yes)
			(effects
				(font
					(size 1.27 1.27)
					(thickness 0.15)
				)
			)
		)
		(property "Author" "Antmicro"
			(at -20.440499 220.141501 0)
			(layer "F.Fab")
			(hide yes)
			(effects
				(font
					(size 1 1)
					(thickness 0.15)
				)
			)
		)
		(property "License" "Apache-2.0"
			(at -20.440499 220.141501 0)
			(layer "F.Fab")
			(hide yes)
			(effects
				(font
					(size 1 1)
					(thickness 0.15)
				)
			)
		)
		(property "MPN" "CR0402-FX-3300GLF"
			(at -20.440499 220.141501 0)
			(layer "F.Fab")
			(hide yes)
			(effects
				(font
					(size 1 1)
					(thickness 0.15)
				)
			)
		)
		(property "Manufacturer" "Bourns"
			(at -20.440499 220.141501 0)
			(layer "F.Fab")
			(hide yes)
			(effects
				(font
					(size 1 1)
					(thickness 0.15)
				)
			)
		)
		(property "Tolerance" "1%"
			(at -20.440499 220.141501 0)
			(layer "F.Fab")
			(hide yes)
			(effects
				(font
					(size 1 1)
					(thickness 0.15)
				)
			)
		)
		(property "Val" "330R"
			(at -20.440499 220.141501 0)
			(layer "F.Fab")
			(hide yes)
			(effects
				(font
					(size 1 1)
					(thickness 0.15)
				)
			)
		)
		(sheetname "/DDR5 SODIMM/")
		(sheetfile "ddr5-sodimm.kicad_sch")
		(attr smd)
		(fp_rect
			(start -0.93 -0.47)
			(end 0.93 0.47)
			(stroke
				(width 0.05)
				(type solid)
			)
			(fill no)
			(layer "F.CrtYd")
		)
		(fp_rect
			(start -0.5 -0.25)
			(end 0.5 0.25)
			(stroke
				(width 0.15)
				(type solid)
			)
			(fill no)
			(layer "F.Fab")
		)
		(pad "1" smd roundrect
			(at -0.485 0 270)
			(size 0.59 0.64)
			(layers "F.Cu" "F.Mask" "F.Paste")
			(roundrect_rratio 0.25)
			(net 302 "Net-(D9-C_{G})")
			(pintype "passive")
		)
		(pad "2" smd roundrect
			(at 0.485 0 270)
			(size 0.59 0.64)
			(layers "F.Cu" "F.Mask" "F.Paste")
			(roundrect_rratio 0.25)
			(net 359 "Net-(Q10-D)")
			(pintype "passive")
		)
	)
	(footprint "antmicro-footprints:C_0402_1005Metric"
		(layer "F.Cu")
		(at 183.120108 163.651)
		(descr "Capacitor SMD 0402")
		(tags "capacitor SMD 0402")
		(property "Reference" "C214"
			(at 0 -0.699 0)
			(layer "F.SilkS")
			(hide yes)
			(effects
				(font
					(size 0.7 0.7)
					(thickness 0.15)
				)
				(justify left bottom)
			)
		)
		(property "Value" "C_100n_0402"
			(at -1.022927 2.155213 0)
			(layer "F.Fab")
			(effects
				(font
					(size 0.7 0.7)
					(thickness 0.15)
				)
				(justify left bottom)
			)
		)
		(property "Datasheet" "https://www.murata.com/products/productdetail?partno=GRM155R61H104KE14%23"
			(at 0 0 0)
			(layer "F.Fab")
			(hide yes)
			(effects
				(font
					(size 1.27 1.27)
					(thickness 0.15)
				)
			)
		)
		(property "Author" "Antmicro"
			(at 0 0 0)
			(layer "F.Fab")
			(hide yes)
			(effects
				(font
					(size 1 1)
					(thickness 0.15)
				)
			)
		)
		(property "Dielectric" "X5R"
			(at 0 0 0)
			(layer "F.Fab")
			(hide yes)
			(effects
				(font
					(size 1 1)
					(thickness 0.15)
				)
			)
		)
		(property "License" "Apache-2.0"
			(at 0 0 0)
			(layer "F.Fab")
			(hide yes)
			(effects
				(font
					(size 1 1)
					(thickness 0.15)
				)
			)
		)
		(property "MPN" "GRM155R61H104KE14D"
			(at 0 0 0)
			(layer "F.Fab")
			(hide yes)
			(effects
				(font
					(size 1 1)
					(thickness 0.15)
				)
			)
		)
		(property "Manufacturer" "Murata"
			(at 0 0 0)
			(layer "F.Fab")
			(hide yes)
			(effects
				(font
					(size 1 1)
					(thickness 0.15)
				)
			)
		)
		(property "Val" "100n"
			(at 0 0 0)
			(layer "F.Fab")
			(hide yes)
			(effects
				(font
					(size 1 1)
					(thickness 0.15)
				)
			)
		)
		(property "Voltage" "50V"
			(at 0 0 0)
			(layer "F.Fab")
			(hide yes)
			(effects
				(font
					(size 1 1)
					(thickness 0.15)
				)
			)
		)
		(sheetname "/Supply/")
		(sheetfile "supply.kicad_sch")
		(attr smd)
		(fp_rect
			(start -0.9659 -0.481258)
			(end 0.9649 0.458742)
			(stroke
				(width 0.05)
				(type solid)
			)
			(fill no)
			(layer "F.CrtYd")
		)
		(fp_line
			(start -0.499 -0.25)
			(end 0.499 -0.25)
			(stroke
				(width 0.15)
				(type solid)
			)
			(layer "F.Fab")
		)
		(fp_line
			(start -0.499 0.248)
			(end -0.499 -0.25)
			(stroke
				(width 0.15)
				(type solid)
			)
			(layer "F.Fab")
		)
		(fp_line
			(start 0.499 -0.25)
			(end 0.499 0.248)
			(stroke
				(width 0.15)
				(type solid)
			)
			(layer "F.Fab")
		)
		(fp_line
			(start 0.499 0.248)
			(end -0.499 0.248)
			(stroke
				(width 0.15)
				(type solid)
			)
			(layer "F.Fab")
		)
		(pad "1" smd roundrect
			(at -0.484 0)
			(size 0.59 0.64)
			(layers "F.Cu" "F.Mask" "F.Paste")
			(roundrect_rratio 0.25)
			(net 200 "+3V3")
			(pintype "passive")
		)
		(pad "2" smd roundrect
			(at 0.484 0)
			(size 0.59 0.64)
			(layers "F.Cu" "F.Mask" "F.Paste")
			(roundrect_rratio 0.25)
			(net 1 "GND")
			(pintype "passive")
		)
	)
	(footprint "antmicro-footprints:LED_0603_1608Metric_G"
		(layer "F.Cu")
		(at 73.5 126.3)
		(descr "LED SMD 0603 Green")
		(tags "LED SMD 0603 Green")
		(property "Reference" "D3"
			(at -0.001 -0.901 0)
			(layer "F.SilkS")
			(hide yes)
			(effects
				(font
					(size 0.7 0.7)
					(thickness 0.15)
				)
				(justify left bottom)
			)
		)
		(property "Value" "LED_G_0603_KP-1608CGCK"
			(at -0.001 1.599 0)
			(layer "F.Fab")
			(effects
				(font
					(size 0.7 0.7)
					(thickness 0.15)
				)
				(justify left bottom)
			)
		)
		(property "Datasheet" "http://www.farnell.com/datasheets/2045956.pdf"
			(at 0 0 0)
			(layer "F.Fab")
			(hide yes)
			(effects
				(font
					(size 1.27 1.27)
					(thickness 0.15)
				)
			)
		)
		(property "Author" "Antmicro"
			(at 0 0 0)
			(layer "F.Fab")
			(hide yes)
			(effects
				(font
					(size 1 1)
					(thickness 0.15)
				)
			)
		)
		(property "License" "Apache-2.0"
			(at 0 0 0)
			(layer "F.Fab")
			(hide yes)
			(effects
				(font
					(size 1 1)
					(thickness 0.15)
				)
			)
		)
		(property "MPN" "KP-1608CGCK"
			(at 0 0 0)
			(layer "F.Fab")
			(hide yes)
			(effects
				(font
					(size 1 1)
					(thickness 0.15)
				)
			)
		)
		(property "Manufacturer" "Kingbright"
			(at 0 0 0)
			(layer "F.Fab")
			(hide yes)
			(effects
				(font
					(size 1 1)
					(thickness 0.15)
				)
			)
		)
		(sheetname "/FPGA Config/")
		(sheetfile "fpga-config.kicad_sch")
		(attr smd)
		(fp_line
			(start -0.271 -0.349)
			(end 0.269 -0.349)
			(stroke
				(width 0.15)
				(type solid)
			)
			(layer "F.SilkS")
		)
		(fp_line
			(start -0.271 0.348)
			(end 0.269 0.348)
			(stroke
				(width 0.15)
				(type solid)
			)
			(layer "F.SilkS")
		)
		(fp_line
			(start -0.107 -0.201)
			(end -0.107 0.198)
			(stroke
				(width 0.1)
				(type solid)
			)
			(layer "F.SilkS")
		)
		(fp_line
			(start -0.107 -0.201)
			(end 0.092 -0.001)
			(stroke
				(width 0.1)
				(type solid)
			)
			(layer "F.SilkS")
		)
		(fp_line
			(start -0.107 -0.001)
			(end -0.291 -0.001)
			(stroke
				(width 0.1)
				(type solid)
			)
			(layer "F.SilkS")
		)
		(fp_line
			(start 0.092 -0.201)
			(end 0.092 0.198)
			(stroke
				(width 0.1)
				(type solid)
			)
			(layer "F.SilkS")
		)
		(fp_line
			(start 0.092 -0.001)
			(end -0.107 0.198)
			(stroke
				(width 0.1)
				(type solid)
			)
			(layer "F.SilkS")
		)
		(fp_line
			(start 0.092 -0.001)
			(end 0.292 -0.001)
			(stroke
				(width 0.1)
				(type solid)
			)
			(layer "F.SilkS")
		)
		(fp_line
			(start 1.249 0.319)
			(end 1.249 -0.321)
			(stroke
				(width 0.15)
				(type solid)
			)
			(layer "F.SilkS")
		)
		(fp_rect
			(start -1.2192 -0.6096)
			(end 1.27 0.6016)
			(stroke
				(width 0.05)
				(type solid)
			)
			(fill no)
			(layer "F.CrtYd")
		)
		(fp_line
			(start -0.849 0.025)
			(end -0.442 0.381)
			(stroke
				(width 0.15)
				(type solid)
			)
			(layer "F.Fab")
		)
		(fp_line
			(start -0.6 -0.001)
			(end -0.202 -0.001)
			(stroke
				(width 0.15)
				(type solid)
			)
			(layer "F.Fab")
		)
		(fp_line
			(start -0.202 -0.201)
			(end -0.202 -0.001)
			(stroke
				(width 0.15)
				(type solid)
			)
			(layer "F.Fab")
		)
		(fp_line
			(start -0.202 -0.001)
			(end -0.202 0.201)
			(stroke
				(width 0.15)
				(type solid)
			)
			(layer "F.Fab")
		)
		(fp_line
			(start -0.202 0.201)
			(end 0.1 -0.001)
			(stroke
				(width 0.15)
				(type solid)
			)
			(layer "F.Fab")
		)
		(fp_line
			(start 0.1 -0.001)
			(end -0.202 -0.201)
			(stroke
				(width 0.15)
				(type solid)
			)
			(layer "F.Fab")
		)
		(fp_line
			(start 0.198 -0.201)
			(end 0.198 -0.101)
			(stroke
				(width 0.15)
				(type solid)
			)
			(layer "F.Fab")
		)
		(fp_line
			(start 0.198 -0.001)
			(end 0.596 -0.001)
			(stroke
				(width 0.15)
				(type solid)
			)
			(layer "F.Fab")
		)
		(fp_line
			(start 0.198 0.201)
			(end 0.198 -0.101)
			(stroke
				(width 0.15)
				(type solid)
			)
			(layer "F.Fab")
		)
		(fp_rect
			(start -0.849 -0.401)
			(end 0.849 0.401)
			(stroke
				(width 0.15)
				(type solid)
			)
			(fill no)
			(layer "F.Fab")
		)
		(pad "1" smd rect
			(at -0.751 -0.001 180)
			(size 0.8 0.8)
			(layers "F.Cu" "F.Mask" "F.Paste")
			(net 200 "+3V3")
			(pinfunction "1")
			(pintype "passive")
		)
		(pad "2" smd rect
			(at 0.749 -0.001 180)
			(size 0.8 0.8)
			(layers "F.Cu" "F.Mask" "F.Paste")
			(net 306 "Net-(D3-Pad2)")
			(pinfunction "2")
			(pintype "passive")
		)
	)
	(footprint "antmicro-footprints:SOT-23-5"
		(layer "F.Cu")
		(at 181.65 190.2 180)
		(property "Reference" "U34"
			(at -1.1 -1.95 0)
			(layer "F.SilkS")
			(effects
				(font
					(size 0.7 0.7)
					(thickness 0.15)
				)
				(justify right top)
			)
		)
		(property "Value" "AT24CS01_SOT23"
			(at 0.002 2.799 0)
			(layer "F.Fab")
			(effects
				(font
					(size 0.7 0.7)
					(thickness 0.15)
				)
				(justify right top)
			)
		)
		(property "Datasheet" "http://ww1.microchip.com/downloads/en/devicedoc/Atmel-8815-SEEPROM-AT24CS01-02-Datasheet.pdf"
			(at 0 0 0)
			(layer "F.Fab")
			(hide yes)
			(effects
				(font
					(size 1.27 1.27)
					(thickness 0.15)
				)
			)
		)
		(property "Description" "EEPROM Memory IC 1Kbit I²C 1 MHz 550 ns SOT-23-5"
			(at 0 0 0)
			(layer "F.Fab")
			(hide yes)
			(effects
				(font
					(size 1.27 1.27)
					(thickness 0.15)
				)
			)
		)
		(property "Manufacturer" "Atmel"
			(at 0 0 180)
			(unlocked yes)
			(layer "F.Fab")
			(hide yes)
			(effects
				(font
					(size 1 1)
					(thickness 0.15)
				)
			)
		)
		(property "MPN" "AT24CS01-ST"
			(at 0 0 180)
			(unlocked yes)
			(layer "F.Fab")
			(hide yes)
			(effects
				(font
					(size 1 1)
					(thickness 0.15)
				)
			)
		)
		(property "Author" "Antmicro"
			(at 0 0 180)
			(unlocked yes)
			(layer "F.Fab")
			(hide yes)
			(effects
				(font
					(size 1 1)
					(thickness 0.15)
				)
			)
		)
		(property "License" "Apache-2.0"
			(at 0 0 180)
			(unlocked yes)
			(layer "F.Fab")
			(hide yes)
			(effects
				(font
					(size 1 1)
					(thickness 0.15)
				)
			)
		)
		(sheetname "/I^{2}C/")
		(sheetfile "i2c.kicad_sch")
		(attr smd)
		(fp_line
			(start 0.8 1.599)
			(end 0.549 1.599)
			(stroke
				(width 0.15)
				(type solid)
			)
			(layer "F.SilkS")
		)
		(fp_line
			(start 0.8 1.3)
			(end 0.8 1.599)
			(stroke
				(width 0.15)
				(type solid)
			)
			(layer "F.SilkS")
		)
		(fp_line
			(start 0.8 0.55)
			(end 0.8 -0.55)
			(stroke
				(width 0.15)
				(type solid)
			)
			(layer "F.SilkS")
		)
		(fp_line
			(start 0.8 -1.3)
			(end 0.8 -1.6)
			(stroke
				(width 0.15)
				(type solid)
			)
			(layer "F.SilkS")
		)
		(fp_line
			(start 0.8 -1.6)
			(end 0.5 -1.6)
			(stroke
				(width 0.15)
				(type solid)
			)
			(layer "F.SilkS")
		)
		(fp_line
			(start -0.55 1.6)
			(end -0.85 1.6)
			(stroke
				(width 0.15)
				(type solid)
			)
			(layer "F.SilkS")
		)
		(fp_line
			(start -0.8 -1.6)
			(end -0.5 -1.6)
			(stroke
				(width 0.15)
				(type solid)
			)
			(layer "F.SilkS")
		)
		(fp_line
			(start -0.8 -1.6)
			(end -0.8 -1.3)
			(stroke
				(width 0.15)
				(type solid)
			)
			(layer "F.SilkS")
		)
		(fp_line
			(start -0.85 1.6)
			(end -0.85 1.301)
			(stroke
				(width 0.15)
				(type solid)
			)
			(layer "F.SilkS")
		)
		(fp_circle
			(center -1.25 -1.5)
			(end -1.2 -1.5)
			(stroke
				(width 0.15)
				(type solid)
			)
			(fill yes)
			(layer "F.SilkS")
		)
		(fp_poly
			(pts
				(xy 1.9 -1.76) (xy 1.9 1.75) (xy -1.9 1.75) (xy -1.9 -1.76)
			)
			(stroke
				(width 0.05)
				(type solid)
			)
			(fill no)
			(layer "F.CrtYd")
		)
		(fp_line
			(start -0.398 -1.525999)
			(end -0.874 -1.05)
			(stroke
				(width 0.15)
				(type solid)
			)
			(layer "F.Fab")
		)
		(fp_poly
			(pts
				(xy 0.874 1.523) (xy 0.874 -1.525) (xy -0.873 -1.525) (xy -0.873 1.523)
			)
			(stroke
				(width 0.15)
				(type solid)
			)
			(fill no)
			(layer "F.Fab")
		)
		(fp_text user "${REFERENCE}"
			(at -1.898 4.299 0)
			(layer "F.Fab")
			(effects
				(font
					(size 0.7 0.7)
					(thickness 0.15)
				)
				(justify right top)
			)
		)
		(fp_text user "Author: Antmicro"
			(at -1.898 5.499 0)
			(layer "F.Fab")
			(effects
				(font
					(size 0.7 0.7)
					(thickness 0.15)
				)
				(justify right top)
			)
		)
		(fp_text user "License: Apache-2.0"
			(at -1.898 6.7 0)
			(layer "F.Fab")
			(effects
				(font
					(size 0.7 0.7)
					(thickness 0.15)
				)
				(justify right top)
			)
		)
		(pad "1" smd rect
			(at -1.351 -0.951 90)
			(size 0.55 1)
			(layers "F.Cu" "F.Mask" "F.Paste")
			(net 762 "Net-(U34-SCL)")
			(pinfunction "SCL")
			(pintype "passive")
		)
		(pad "2" smd rect
			(at -1.351 0 90)
			(size 0.55 1)
			(layers "F.Cu" "F.Mask" "F.Paste")
			(net 1 "GND")
			(pinfunction "GND")
			(pintype "passive")
		)
		(pad "3" smd rect
			(at -1.351 0.949 90)
			(size 0.55 1)
			(layers "F.Cu" "F.Mask" "F.Paste")
			(net 761 "Net-(U34-SDA)")
			(pinfunction "SDA")
			(pintype "passive")
		)
		(pad "4" smd rect
			(at 1.35 0.949 90)
			(size 0.55 1)
			(layers "F.Cu" "F.Mask" "F.Paste")
			(net 759 "Net-(D17-C)")
			(pinfunction "VCC")
			(pintype "passive")
		)
		(pad "5" smd rect
			(at 1.35 -0.951 90)
			(size 0.55 1)
			(layers "F.Cu" "F.Mask" "F.Paste")
			(net 1 "GND")
			(pinfunction "WP")
			(pintype "passive")
		)
	)
	(footprint "antmicro-footprints:C_0805_2012Metric"
		(layer "F.Cu")
		(at 203.395501 184.4605 90)
		(descr "Capacitor SMD 0805")
		(tags "capacitor SMD 0805")
		(property "Reference" "C171"
			(at -2.10551 -1.198678 90)
			(layer "F.SilkS")
			(hide yes)
			(effects
				(font
					(size 0.7 0.7)
					(thickness 0.15)
				)
				(justify left bottom)
			)
		)
		(property "Value" "C_22u_25V_0805"
			(at -2.055717 1.963152 90)
			(layer "F.Fab")
			(effects
				(font
					(size 0.7 0.7)
					(thickness 0.15)
				)
				(justify left bottom)
			)
		)
		(property "Datasheet" "https://product.samsungsem.com/mlcc/CL21A226MAYNNN.do"
			(at 0 0 90)
			(layer "F.Fab")
			(hide yes)
			(effects
				(font
					(size 1.27 1.27)
					(thickness 0.15)
				)
			)
		)
		(property "Author" "Antmicro"
			(at 387.856001 -18.935001 0)
			(layer "F.Fab")
			(hide yes)
			(effects
				(font
					(size 1 1)
					(thickness 0.15)
				)
			)
		)
		(property "Dielectric" ""
			(at 387.856001 -18.935001 0)
			(layer "F.Fab")
			(hide yes)
			(effects
				(font
					(size 1 1)
					(thickness 0.15)
				)
			)
		)
		(property "License" "Apache-2.0"
			(at 387.856001 -18.935001 0)
			(layer "F.Fab")
			(hide yes)
			(effects
				(font
					(size 1 1)
					(thickness 0.15)
				)
			)
		)
		(property "MPN" "CL21A226MAYNNNE"
			(at 387.856001 -18.935001 0)
			(layer "F.Fab")
			(hide yes)
			(effects
				(font
					(size 1 1)
					(thickness 0.15)
				)
			)
		)
		(property "Manufacturer" "Samsung Electro-Mechanics"
			(at 387.856001 -18.935001 0)
			(layer "F.Fab")
			(hide yes)
			(effects
				(font
					(size 1 1)
					(thickness 0.15)
				)
			)
		)
		(property "Val" "22u_25V"
			(at 387.856001 -18.935001 0)
			(layer "F.Fab")
			(hide yes)
			(effects
				(font
					(size 1 1)
					(thickness 0.15)
				)
			)
		)
		(property "Voltage" ""
			(at 387.856001 -18.935001 0)
			(layer "F.Fab")
			(hide yes)
			(effects
				(font
					(size 1 1)
					(thickness 0.15)
				)
			)
		)
		(sheetname "/Supply/")
		(sheetfile "supply.kicad_sch")
		(attr smd)
		(fp_line
			(start -0.3 -0.8)
			(end 0.3 -0.8)
			(stroke
				(width 0.15)
				(type solid)
			)
			(layer "F.SilkS")
		)
		(fp_line
			(start -0.3 0.8)
			(end 0.3 0.8)
			(stroke
				(width 0.15)
				(type solid)
			)
			(layer "F.SilkS")
		)
		(fp_rect
			(start -1.9 -0.93)
			(end 1.9 0.93)
			(stroke
				(width 0.05)
				(type solid)
			)
			(fill no)
			(layer "F.CrtYd")
		)
		(fp_rect
			(start -0.95 -0.675)
			(end 0.95 0.675)
			(stroke
				(width 0.15)
				(type solid)
			)
			(fill no)
			(layer "F.Fab")
		)
		(pad "1" smd rect
			(at -1.05 0 90)
			(size 1.2 1.2)
			(layers "F.Cu" "F.Mask" "F.Paste")
			(net 1 "GND")
			(pintype "passive")
		)
		(pad "2" smd rect
			(at 1.05 0 90)
			(size 1.2 1.2)
			(layers "F.Cu" "F.Mask" "F.Paste")
			(net 38 "VDC")
			(pintype "passive")
		)
	)
)
